# BASEBOARD_FAB2 (Tioga Pass) — schematic netlist excerpt (pin names and nets, part order shuffled) for the footprints in the layout excerpt that follows; sources: Cadence DE-HDL packaged netlist, KiCad conversion of Wiwynn_Tioga_Pass_MB.brd

C5G102  CAP_A  22.0UF 4V 20% X6S  pkg 0603V  page 243 : A = PVDDQ_KLM ; B = GND
R7W19  RES  4.75K 1% CHIP  pkg 0402  page 118 : A = P3V3_STBY ; B = FM_BATTERY_SENSE_EN_R_N

Q9W2  NPN  MMBT3904 IC  pkg SM  page 249
  B  = FM_TPM_PRES_RST_N_R
  E  = GND
  C  = FM_TPM_PRES_RST

(kicad_pcb
	(version 20260206)
	(generator "pcbnew")
	(generator_version "10.0")
	(general
		(thickness 1.6)
		(legacy_teardrops no)
	)
	(paper "A4")
	(title_block
		(title "Wiwynn_Tioga_Pass_MB.brd")
		(comment 1 "Tioga Pass / footprints 3736-3738 of 4770")
	)
	(layers
		(0 "F.Cu" signal "TOP")
		(4 "In1.Cu" signal "L2GND")
		(6 "In2.Cu" signal "L3")
		(8 "In3.Cu" signal "L4GND")
		(10 "In4.Cu" signal "L5")
		(12 "In5.Cu" signal "L6GND")
		(14 "In6.Cu" signal "L7VCC")
		(16 "In7.Cu" signal "L8VCC")
		(18 "In8.Cu" signal "L9GND")
		(20 "In9.Cu" signal "L10")
		(22 "In10.Cu" signal "L11GND")
		(24 "In11.Cu" signal "L12")
		(26 "In12.Cu" signal "L13GND")
		(2 "B.Cu" signal "BOTTOM")
		(9 "F.Adhes" user "F.Adhesive")
		(11 "B.Adhes" user "B.Adhesive")
		(13 "F.Paste" user "Package Geometry/Pastemask Top")
		(15 "B.Paste" user "Package Geometry/Pastemask Bottom")
		(5 "F.SilkS" user "Ref Des/Silkscreen Top")
		(7 "B.SilkS" user "Ref Des/Silkscreen Bottom")
		(1 "F.Mask" user "Board Geometry/Soldermask Top")
		(3 "B.Mask" user "Board Geometry/Soldermask Bottom")
		(17 "Dwgs.User" user "User.Drawings")
		(19 "Cmts.User" user "User.Comments")
		(21 "Eco1.User" user "User.Eco1")
		(23 "Eco2.User" user "User.Eco2")
		(25 "Edge.Cuts" user "Board Geometry/Outline")
		(27 "Margin" user)
		(31 "F.CrtYd" user "Package Geometry/Place Bound Top")
		(29 "B.CrtYd" user "Package Geometry/Place Bound Bottom")
		(35 "F.Fab" user "Ref Des/Assembly Top")
		(33 "B.Fab" user "Ref Des/Assembly Bottom")
	)
	(footprint ""
		(layer "B.Cu")
		(at 101.3968 -149.8092 90)
		(property "Reference" "C5G102"
			(at -1.14681 0.76708 180)
			(unlocked yes)
			(layer "B.SilkS")
			(effects
				(font
					(size 0.7874 0.5842)
					(thickness 0.1524)
				)
				(justify mirror)
			)
		)
		(property "Value" ""
			(at 0 0 90)
			(layer "B.Fab")
			(effects
				(font
					(size 1.27 1.27)
				)
				(justify mirror)
			)
		)
		(duplicate_pad_numbers_are_jumpers no)
		(fp_rect
			(start -0.4953 -0.2032)
			(end 0.4953 1.6002)
			(stroke
				(width 0)
				(type default)
			)
			(fill no)
			(layer "B.CrtYd")
		)
		(fp_line
			(start 0.4953 -0.2032)
			(end -0.4953 -0.2032)
			(stroke
				(width 0.1)
				(type default)
			)
			(layer "B.Fab")
		)
		(fp_line
			(start -0.4953 -0.2032)
			(end -0.4953 1.6002)
			(stroke
				(width 0.1)
				(type default)
			)
			(layer "B.Fab")
		)
		(fp_line
			(start 0.4953 1.6002)
			(end 0.4953 -0.2032)
			(stroke
				(width 0.1)
				(type default)
			)
			(layer "B.Fab")
		)
		(fp_line
			(start -0.4953 1.6002)
			(end 0.4953 1.6002)
			(stroke
				(width 0.1)
				(type default)
			)
			(layer "B.Fab")
		)
		(pad "1" smd rect
			(at 0 0 270)
			(size 0.762 0.889)
			(layers "B.Cu" "B.Mask" "B.Paste")
			(net "PVDDQ_KLM")
		)
		(pad "2" smd rect
			(at 0 1.397 270)
			(size 0.762 0.889)
			(layers "B.Cu" "B.Mask" "B.Paste")
			(net "GND")
		)
		(zone
			(layer "B.Cu")
			(hatch none 0.5)
			(connect_pads
				(clearance 0)
			)
			(min_thickness 0.25)
			(keepout
				(tracks not_allowed)
				(vias allowed)
				(pads allowed)
				(copperpour not_allowed)
				(footprints allowed)
			)
			(placement
				(enabled no)
				(sheetname "")
			)
			(fill
				(thermal_gap 0.5)
				(thermal_bridge_width 0.5)
				(island_removal_mode 0)
			)
			(polygon
				(pts
					(xy 101.8413 -149.4282) (xy 102.3493 -149.4282) (xy 102.3493 -150.1902) (xy 101.8413 -150.1902)
				)
			)
		)
	)
	(footprint ""
		(layer "B.Cu")
		(at 374.84177 -95.568516 90)
		(property "Reference" "R7W19"
			(at 0.8382 -0.67818 90)
			(unlocked yes)
			(layer "B.SilkS")
			(effects
				(font
					(size 0.4064 0.254)
					(thickness 0.1524)
				)
				(justify left mirror)
			)
		)
		(property "Value" ""
			(at 0 0 90)
			(layer "B.Fab")
			(effects
				(font
					(size 1.27 1.27)
				)
				(justify mirror)
			)
		)
		(duplicate_pad_numbers_are_jumpers no)
		(fp_poly
			(pts
				(xy 0.2794 -0.1016) (xy -0.2794 -0.1016) (xy -0.2794 0.9906) (xy 0.2794 0.9906)
			)
			(stroke
				(width 0)
				(type default)
			)
			(fill no)
			(layer "B.CrtYd")
		)
		(fp_line
			(start 0.2794 -0.1016)
			(end 0.2794 0.9906)
			(stroke
				(width 0.1)
				(type default)
			)
			(layer "B.Fab")
		)
		(fp_line
			(start -0.2794 -0.1016)
			(end 0.2794 -0.1016)
			(stroke
				(width 0.1)
				(type default)
			)
			(layer "B.Fab")
		)
		(fp_line
			(start 0.2794 0.9906)
			(end -0.2794 0.9906)
			(stroke
				(width 0.1)
				(type default)
			)
			(layer "B.Fab")
		)
		(fp_line
			(start -0.2794 0.9906)
			(end -0.2794 -0.1016)
			(stroke
				(width 0.1)
				(type default)
			)
			(layer "B.Fab")
		)
		(pad "1" smd rect
			(at 0 0 270)
			(size 0.508 0.508)
			(layers "B.Cu" "B.Mask" "B.Paste")
			(net "P3V3_STBY")
		)
		(pad "2" smd rect
			(at 0 0.889 270)
			(size 0.508 0.508)
			(layers "B.Cu" "B.Mask" "B.Paste")
			(net "FM_BATTERY_SENSE_EN_R_N")
		)
		(zone
			(layer "B.Cu")
			(hatch none 0.5)
			(connect_pads
				(clearance 0)
			)
			(min_thickness 0.25)
			(keepout
				(tracks allowed)
				(vias not_allowed)
				(pads allowed)
				(copperpour not_allowed)
				(footprints allowed)
			)
			(placement
				(enabled no)
				(sheetname "")
			)
			(fill
				(thermal_gap 0.5)
				(thermal_bridge_width 0.5)
				(island_removal_mode 0)
			)
			(polygon
				(pts
					(xy 375.09577 -95.822516) (xy 375.09577 -95.314516) (xy 375.47677 -95.314516) (xy 375.47677 -95.822516)
				)
			)
		)
		(zone
			(layer "B.Cu")
			(hatch none 0.5)
			(connect_pads
				(clearance 0)
			)
			(min_thickness 0.25)
			(keepout
				(tracks not_allowed)
				(vias allowed)
				(pads allowed)
				(copperpour not_allowed)
				(footprints allowed)
			)
			(placement
				(enabled no)
				(sheetname "")
			)
			(fill
				(thermal_gap 0.5)
				(thermal_bridge_width 0.5)
				(island_removal_mode 0)
			)
			(polygon
				(pts
					(xy 375.47677 -95.822516) (xy 375.47677 -95.314516) (xy 375.09577 -95.314516) (xy 375.09577 -95.822516)
				)
			)
		)
	)
	(footprint ""
		(layer "B.Cu")
		(at 442.8871 -20.8788)
		(property "Reference" "Q9W2"
			(at 0.229362 -1.2065 0)
			(unlocked yes)
			(layer "B.SilkS")
			(effects
				(font
					(size 0.4064 0.254)
					(thickness 0.1524)
				)
				(justify left mirror)
			)
		)
		(property "Value" ""
			(at 0 0 0)
			(layer "B.Fab")
			(effects
				(font
					(size 1.27 1.27)
				)
				(justify mirror)
			)
		)
		(duplicate_pad_numbers_are_jumpers no)
		(fp_line
			(start -1.778 -0.5715)
			(end -1.778 0.3175)
			(stroke
				(width 0.1524)
				(type default)
			)
			(layer "B.SilkS")
		)
		(fp_line
			(start -1.778 2.4765)
			(end -1.778 1.5875)
			(stroke
				(width 0.1524)
				(type default)
			)
			(layer "B.SilkS")
		)
		(fp_line
			(start -0.9525 -0.5715)
			(end -1.778 -0.5715)
			(stroke
				(width 0.1524)
				(type default)
			)
			(layer "B.SilkS")
		)
		(fp_line
			(start -0.9525 2.4765)
			(end -1.778 2.4765)
			(stroke
				(width 0.1524)
				(type default)
			)
			(layer "B.SilkS")
		)
		(fp_line
			(start -0.381 0.635)
			(end -0.381 1.27)
			(stroke
				(width 0.1524)
				(type default)
			)
			(layer "B.SilkS")
		)
		(fp_circle
			(center 0.9525 -0.9271)
			(end 1.0795 -0.9271)
			(stroke
				(width 0.254)
				(type default)
			)
			(fill no)
			(layer "B.SilkS")
		)
		(fp_poly
			(pts
				(xy -1.778 2.4765) (xy -0.381 2.4765) (xy -0.381 -0.5715) (xy -1.778 -0.5715)
			)
			(stroke
				(width 0)
				(type default)
			)
			(fill no)
			(layer "B.CrtYd")
		)
		(fp_line
			(start -1.778 -0.5715)
			(end -0.381 -0.5715)
			(stroke
				(width 0.1)
				(type default)
			)
			(layer "B.Fab")
		)
		(fp_line
			(start -1.778 2.4765)
			(end -1.778 -0.5715)
			(stroke
				(width 0.1)
				(type default)
			)
			(layer "B.Fab")
		)
		(fp_line
			(start -0.381 -0.5715)
			(end -0.381 2.4765)
			(stroke
				(width 0.1)
				(type default)
			)
			(layer "B.Fab")
		)
		(fp_line
			(start -0.381 2.4765)
			(end -1.778 2.4765)
			(stroke
				(width 0.1)
				(type default)
			)
			(layer "B.Fab")
		)
		(fp_circle
			(center 0.9525 -0.9271)
			(end 1.0795 -0.9271)
			(stroke
				(width 0.254)
				(type default)
			)
			(fill no)
			(layer "B.Fab")
		)
		(pad "1" smd rect
			(at 0 0 180)
			(size 1.143 0.508)
			(layers "B.Cu" "B.Mask" "B.Paste")
			(net "FM_TPM_PRES_RST_N_R")
		)
		(pad "2" smd rect
			(at 0 1.905 180)
			(size 1.143 0.508)
			(layers "B.Cu" "B.Mask" "B.Paste")
			(net "GND")
		)
		(pad "3" smd rect
			(at -2.159 0.9525 180)
			(size 1.143 0.508)
			(layers "B.Cu" "B.Mask" "B.Paste")
			(net "FM_TPM_PRES_RST")
		)
	)
)
